FILE_TYPE = MULTI_PHYS_TABLE;

PART 'RAA229620GNPHA0'

{========================================================================================}
:VALUE              | PART_TYPE | MATERIAL | PART_NUMBER    = STANDARD        | LIFECYCLE          | PART_NUMBER   | JEDEC_TYPE           | DESCRIPTION                                                                        | MANUFTR | MANUF_PN           | RD_CMPLS_LVL | CMPLS_LVL | FROM_PJ     | CLASS | DIP_SMD | DATA                                                          | EE_CHECK_LIST | FP_ECN                   | PSL | CREATOR | STATUS | MSD  | ESD_CDM | ESD_HBM | ESD_MM | PIN_LENGTH_SHORT_PIN | PIN_LENGTH_LONG_PIN | CREATEDAY  ;
{========================================================================================}
 'RAA229620GNP#HA0' | 'SMLF'    | 'IC'     | 'AL229620000'(!) = ''              | ''                 | 'AL229620000' |'QFN48_TH_0-4_6X6XH'| 'IC(48P)RAA229620GNP#HA0(QFN)'                                                     | 'RTT'   | 'RAA229620GNP#HA0' | 'EP(V1)'     | ''        | 'S5N-YC'    | 'IC'  | ''      | 'RTT_RAA229620GNPHA0.pdf'                                     | ''            | ''                       | ''  | ''      | ''     | 'NA' | 'NA'    | 'NA'    | 'NA'   | '0 MILS'             | '0 MILS'            | '20201118'
 'RAA229620GNP#HA0' | 'SMLF'    | 'EMPTY'  | 'AL229620000'(!) = ''              | ''                 | 'AL229620000' |'QFN48_TH_0-4_6X6XH'| 'IC(48P)RAA229620GNP#HA0(QFN)'                                                     | 'RTT'   | 'RAA229620GNP#HA0' | 'EP(V1)'     | ''        | 'S5N-YC'    | 'IC'  | ''      | 'RTT_RAA229620GNPHA0.pdf'                                     | ''            | ''                       | ''  | ''      | ''     | 'NA' | 'NA'    | 'NA'    | 'NA'   | '0 MILS'             | '0 MILS'            | '20201118'
 'RAA229620GNP#HA0' | 'SMLF'    | 'IC'     | 'AR0S6ZPS000'(!) = ''              | ''                 | 'AR0S6ZPS000' |'QFN48_TH_0-4_6X6XH'| 'PROG IC(49P)RAA229620GNP#HA0(QFN) (checksum:C1F8669F/54AD703F/DC02BFA8)'          | 'RTT'   | 'RAA229620GNP#HA0' | 'EP(V1)'     | ''        | 'S6Z-OSCAR' | 'IC'  | ''      | 'RTT_RAA229620GNPHA0_C1F8669F_54AD703F_DC02BFA8.pdf'          | ''            | ''                       | ''  | ''      | ''     | ''   | ''      | ''      | ''     | '0 MILS'             | '0 MILS'            | '20210705'
 'RAA229620GNP#HA0' | 'SMLF'    | 'EMPTY'  | 'AR0S6ZPS000'(!) = ''              | ''                 | 'AR0S6ZPS000' |'QFN48_TH_0-4_6X6XH'| 'PROG IC(49P)RAA229620GNP#HA0(QFN) (checksum:C1F8669F/54AD703F/DC02BFA8)'          | 'RTT'   | 'RAA229620GNP#HA0' | 'EP(V1)'     | ''        | 'S6Z-OSCAR' | 'IC'  | ''      | 'RTT_RAA229620GNPHA0_C1F8669F_54AD703F_DC02BFA8.pdf'          | ''            | ''                       | ''  | ''      | ''     | ''   | ''      | ''      | ''     | '0 MILS'             | '0 MILS'            | '20210705'
 'RAA229620GNP#HA0' | 'SMLF'    | 'IC'     | 'AR0T6GPV003'(!) = ''              | ''                 | 'AR0T6GPV003' |'QFN48_TH_0-4_6X6XH'| 'PROG IC(49P)RAA229620GNP#HA0(QFN) (checksum:3A83DCB6/E9DE6F27)'                   | 'RTT'   | 'RAA229620GNP#HA0' | 'EP(V1)'     | ''        | 'T6G-OSCAR' | 'IC'  | ''      | 'RTT_RAA229620GNPHA0_3A83DCB6_E9DE6F27.pdf'                   | ''            | ''                       | ''  | ''      | ''     | ''   | ''      | ''      | ''     | '0 MILS'             | '0 MILS'            | '20210729'
 'RAA229620GNP#HA0' | 'SMLF'    | 'EMPTY'  | 'AR0T6GPV003'(!) = ''              | ''                 | 'AR0T6GPV003' |'QFN48_TH_0-4_6X6XH'| 'PROG IC(49P)RAA229620GNP#HA0(QFN) (checksum:3A83DCB6/E9DE6F27)'                   | 'RTT'   | 'RAA229620GNP#HA0' | 'EP(V1)'     | ''        | 'T6G-OSCAR' | 'IC'  | ''      | 'RTT_RAA229620GNPHA0_3A83DCB6_E9DE6F27.pdf'                   | ''            | ''                       | ''  | ''      | ''     | ''   | ''      | ''      | ''     | '0 MILS'             | '0 MILS'            | '20210729'
 'RAA229620GNP#HA0' | 'SMLF'    | 'IC'     | 'AR0T6GPV005'(!) = ''              | ''                 | 'AR0T6GPV005' |'QFN48_TH_0-4_6X6XH'| 'PROG IC(49P)RAA229620GNP#HA0(QFN) (checksum:E9CB2411/89828B88/A762B9D2)'          | 'RTT'   | 'RAA229620GNP#HA0' | 'EP(V1)'     | 'EP(V1)'  | 'T6G-NINA'  | 'IC'  | ''      | 'RTT_RAA229620GNPHA0_E9CB2411_89828B88_A762B9D2.pdf'          | ''            | ''                       | ''  | ''      | ''     | ''   | ''      | ''      | ''     | '0 MILS'             | '0 MILS'            | '20211025'
 'RAA229620GNP#HA0' | 'SMLF'    | 'EMPTY'  | 'AR0T6GPV005'(!) = ''              | ''                 | 'AR0T6GPV005' |'QFN48_TH_0-4_6X6XH'| 'PROG IC(49P)RAA229620GNP#HA0(QFN) (checksum:E9CB2411/89828B88/A762B9D2)'          | 'RTT'   | 'RAA229620GNP#HA0' | 'EP(V1)'     | 'EP(V1)'  | 'T6G-NINA'  | 'IC'  | ''      | 'RTT_RAA229620GNPHA0_E9CB2411_89828B88_A762B9D2.pdf'          | ''            | ''                       | ''  | ''      | ''     | ''   | ''      | ''      | ''     | '0 MILS'             | '0 MILS'            | '20211025'
 'RAA229620GNP#HA0' | 'SMLF'    | 'IC'     | 'AR0A5GP6003'(!) = ''              | ''                 | 'AR0A5GP6003' |'QFN48_TH_0-4_6X6XH'| 'PROG IC(49P)RAA229620GNP#HA0(QFN) (checksum:6BD54998/8178D734)'                   | 'RTT'   | 'RAA229620GNP#HA0' | 'EP(V1)'     | 'EP(V1)'  | 'A5G-OSCAR' | 'IC'  | ''      | 'RTT_RAA229620GNPHA0_6BD54998_8178D734.pdf'                   | ''            | ''                       | ''  | ''      | ''     | ''   | ''      | ''      | ''     | '0 MILS'             | '0 MILS'            | '20211201'
 'RAA229620GNP#HA0' | 'SMLF'    | 'EMPTY'  | 'AR0A5GP6003'(!) = ''              | ''                 | 'AR0A5GP6003' |'QFN48_TH_0-4_6X6XH'| 'PROG IC(49P)RAA229620GNP#HA0(QFN) (checksum:6BD54998/8178D734)'                   | 'RTT'   | 'RAA229620GNP#HA0' | 'EP(V1)'     | 'EP(V1)'  | 'A5G-OSCAR' | 'IC'  | ''      | 'RTT_RAA229620GNPHA0_6BD54998_8178D734.pdf'                   | ''            | ''                       | ''  | ''      | ''     | ''   | ''      | ''      | ''     | '0 MILS'             | '0 MILS'            | '20211201'
 'RAA229620GNP#HA0' | 'SMLF'    | 'IC'     | 'AR0T6GPV008'(!) = ''              | ''                 | 'AR0T6GPV008' |'QFN48_TH_0-4_6X6XH'| 'PROG IC(48P)RAA229620GNP#HA0(QFN) (checksum:E9FCC405/4AC86131/34AFF3D6)'          | 'RTT'   | 'RAA229620GNP#HA0' | 'EP(V1)'     | 'EP(V1)'  | 'T6G-DAVID' | 'IC'  | ''      | 'RTT_RAA229620GNPHA0_E9FCC405_4AC86131_34AFF3D6.pdf'          | ''            | ''                       | ''  | ''      | ''     | ''   | ''      | ''      | ''     | '0 MILS'             | '0 MILS'            | '20220225'
 'RAA229620GNP#HA0' | 'SMLF'    | 'EMPTY'  | 'AR0T6GPV008'(!) = ''              | ''                 | 'AR0T6GPV008' |'QFN48_TH_0-4_6X6XH'| 'PROG IC(48P)RAA229620GNP#HA0(QFN) (checksum:E9FCC405/4AC86131/34AFF3D6)'          | 'RTT'   | 'RAA229620GNP#HA0' | 'EP(V1)'     | 'EP(V1)'  | 'T6G-DAVID' | 'IC'  | ''      | 'RTT_RAA229620GNPHA0_E9FCC405_4AC86131_34AFF3D6.pdf'          | ''            | ''                       | ''  | ''      | ''     | ''   | ''      | ''      | ''     | '0 MILS'             | '0 MILS'            | '20220225'
 'RAA229620GNP#HA0' | 'SMLF'    | 'IC'     | 'AR0S6ZPS015'(!) = ''              | ''                 | 'AR0S6ZPS015' |'QFN48_TH_0-4_6X6XH'| 'PROG IC(49P)RAA229620GNP#HA0(QFN) (checksum:DE7AE5D9/4C893BA7/1FEEB77E/CF55C868)' | 'RTT'   | 'RAA229620GNP#HA0' | 'EP(V1)'     | 'EP(V1)'  | 'S6Z-OSCAR' | 'IC'  | ''      | 'RTT_RAA229620GNPHA0_DE7AE5D9_4C893BA7_1FEEB77E_CF55C868.pdf' | ''            | ''                       | ''  | ''      | ''     | ''   | ''      | ''      | ''     | '0 MILS'             | '0 MILS'            | '20220317'
 'RAA229620GNP#HA0' | 'SMLF'    | 'EMPTY'  | 'AR0S6ZPS015'(!) = ''              | ''                 | 'AR0S6ZPS015' |'QFN48_TH_0-4_6X6XH'| 'PROG IC(49P)RAA229620GNP#HA0(QFN) (checksum:DE7AE5D9/4C893BA7/1FEEB77E/CF55C868)' | 'RTT'   | 'RAA229620GNP#HA0' | 'EP(V1)'     | 'EP(V1)'  | 'S6Z-OSCAR' | 'IC'  | ''      | 'RTT_RAA229620GNPHA0_DE7AE5D9_4C893BA7_1FEEB77E_CF55C868.pdf' | ''            | ''                       | ''  | ''      | ''     | ''   | ''      | ''      | ''     | '0 MILS'             | '0 MILS'            | '20220317'
 'RAA229620GNP#HA0' | 'SMLF'    | 'IC'     | 'ARF0TGP4000'(!) = ''              | ''                 | 'ARF0TGP4000' |'QFN48_TH_0-4_6X6XH'| 'PROG IC(49P)RAA229620GNP#HA0(QFN) (checksum:BAE585D1/84B0972A)'                   | 'RTT'   | 'RAA229620GNP#HA0' | 'EP(V1)'     | 'EP(V1)'  | 'F0TG-CART' | 'IC'  | ''      | 'RTT_RAA229620GNPHA0_BAE585D1_84B0972A.pdf'                   | ''            | 'QFN48_TH_0-4_6X6XH.msg' | ''  | ''      | ''     | ''   | ''      | ''      | ''     | '0 MILS'             | '0 MILS'            | '20220615'
 'RAA229620GNP#HA0' | 'SMLF'    | 'EMPTY'  | 'ARF0TGP4000'(!) = ''              | ''                 | 'ARF0TGP4000' |'QFN48_TH_0-4_6X6XH'| 'PROG IC(49P)RAA229620GNP#HA0(QFN) (checksum:BAE585D1/84B0972A)'                   | 'RTT'   | 'RAA229620GNP#HA0' | 'EP(V1)'     | 'EP(V1)'  | 'F0TG-CART' | 'IC'  | ''      | 'RTT_RAA229620GNPHA0_BAE585D1_84B0972A.pdf'                   | ''            | 'QFN48_TH_0-4_6X6XH.msg' | ''  | ''      | ''     | ''   | ''      | ''      | ''     | '0 MILS'             | '0 MILS'            | '20220615'
 'RAA229620GNP#HA0' | 'SMLF'    | 'IC'     | 'ARF0TGP4002'(!) = ''              | ''                 | 'ARF0TGP4002' |'QFN48_TH_0-4_6X6XH'| 'PROG IC(49P)RAA229620GNP#HA0(QFN) (checksum:C6AD1D27/9A3E4D0C)'                   | 'RTT'   | 'RAA229620GNP#HA0' | 'EP(V1)'     | 'EP(V1)'  | 'F0TG-CART' | 'IC'  | ''      | 'RTT_RAA229620GNPHA0_C6AD1D27_9A3E4D0C.pdf'                   | ''            | 'QFN48_TH_0-4_6X6XH.msg' | ''  | ''      | ''     | ''   | ''      | ''      | ''     | '0 MILS'             | '0 MILS'            | '20221205'
 'RAA229620GNP#HA0' | 'SMLF'    | 'EMPTY'  | 'ARF0TGP4002'(!) = ''              | ''                 | 'ARF0TGP4002' |'QFN48_TH_0-4_6X6XH'| 'PROG IC(49P)RAA229620GNP#HA0(QFN) (checksum:C6AD1D27/9A3E4D0C)'                   | 'RTT'   | 'RAA229620GNP#HA0' | 'EP(V1)'     | 'EP(V1)'  | 'F0TG-CART' | 'IC'  | ''      | 'RTT_RAA229620GNPHA0_C6AD1D27_9A3E4D0C.pdf'                   | ''            | 'QFN48_TH_0-4_6X6XH.msg' | ''  | ''      | ''     | ''   | ''      | ''      | ''     | '0 MILS'             | '0 MILS'            | '20221205'
 'RAA229620GNP#HA0' | 'SMLF'    | 'IC'     | 'ARF0TGP4008'(!) = ''               | ''               | 'ARF0TGP4008' |'QFN48_TH_0-4_6X6XH'| 'PROG IC(49P)RAA229620GNP#HA0(QFN) (checksum:76E9CB07/81A0F2C3)'                   | 'RTT'   | 'RAA229620GNP#HA0' | 'EP(V1)'     | 'EP(V1)'  | 'F0TG-CART' | 'IC'  | ''      | 'RTT_RAA229620GNPHA0_76E9CB07_81A0F2C3.pdf'                   | ''            | 'QFN48_TH_0-4_6X6XH.msg' | ''  | ''      | ''     | ''   | ''      | ''      | ''     | '0 MILS'             | '0 MILS'            | '20230325'
 'RAA229620GNP#HA0' | 'SMLF'    | 'EMPTY'  | 'ARF0TGP4008'(!) = ''               | ''               | 'ARF0TGP4008' |'QFN48_TH_0-4_6X6XH'| 'PROG IC(49P)RAA229620GNP#HA0(QFN) (checksum:76E9CB07/81A0F2C3)'                   | 'RTT'   | 'RAA229620GNP#HA0' | 'EP(V1)'     | 'EP(V1)'  | 'F0TG-CART' | 'IC'  | ''      | 'RTT_RAA229620GNPHA0_76E9CB07_81A0F2C3.pdf'                   | ''            | 'QFN48_TH_0-4_6X6XH.msg' | ''  | ''      | ''     | ''   | ''      | ''      | ''     | '0 MILS'             | '0 MILS'            | '20230325'

END_PART

END.

